FILE_TYPE = CONNECTIVITY;
{Allegro Design Entry HDL 17.2-2016 S081 (4005846) 1/11/2022}
"PAGE_NUMBER" = 256;
0"NC";
1"PVCCIN_CPU0\g";
2"SW_P12V_PVCCIN_CPU0_FLT\g";
3"PVCCIN_CPU0\g";
4"SW_P12V_PVCCIN_CPU0_FLT\g";
5"PVCCIN_CPU0_PVCC\g";
6"PVCCIN_CPU0_PVCC\g";
7"GND\g";
8"GND\g";
9"GND\g";
10"GND\g";
11"GND\g";
12"GND\g";
13"GND\g";
14"GND\g";
15"GND\g";
16"GND\g";
17"GND\g";
18"GND\g";
19"GND\g";
20"GND\g";
21"GND\g";
22"GND\g";
23"PVCCIN_CPU0_IMON8";
24"PVCCIN_CPU0_VREF"CDS_PHYS_NET_NAME"PVCCIN_CPU0_VREF";
25"PVCCIN_CPU0_VDD8";
26"SW_PVCCIN_CPU0_BOOT8";
27"SW_PVCCIN_CPU0_BOOT8_R";
28"IND_P0_CPL7";
29"SW_PVCCIN_CPU0_BOOT7_R";
30"SW_PVCCIN_CPU0_BOOT7";
31"SW_PVCCIN_CPU0_BOOTR7";
32"SW_PVCCIN_CPU0_SW7";
33"PVCCIN_CPU0_VDD7";
34"PVCCIN_CPU0_LSET7";
35"PVCCIN_CPU0_VREF"CDS_PHYS_NET_NAME"PVCCIN_CPU0_VREF";
36"PVCCIN_CPU0_ATSEN";
37"PVCCIN_CPU0_IMON7";
38"PVCCIN_CPU0_VOS7";
39"IND_P0_CPL6";
40"SW_PVCCIN_CPU0_BOOTR8";
41"SW_PVCCIN_CPU0_SW8";
42"IND_P0_CPL8";
43"PVCCIN_CPU0_PWM7";
44"PVCCIN_CPU0_VOS8";
45"PVCCIN_CPU0_PWM8";
46"PVCCIN_CPU0_ATSEN";
47"PVCCIN_CPU0_LSET8";
%"UNIVERSAL_GND"
"1","(-7550,-6125)","0","logical_power","I1";
;
CDS_LIB"logical_power"
HDL_POWER"GND"
ROOM"VR_CORE0_CTRL";
"A"22;
%"UNIVERSAL_GND"
"1","(-7150,-5150)","0","logical_power","I10";
;
CDS_LIB"logical_power"
HDL_POWER"GND"
ROOM"VR_CORE0_CTRL";
"A"20;
%"Q_CAP"
"1","(-7150,-4900)","0","pure_quanta","I11";
;
PART_NUMBER"CH5222KEB01"
MATERIAL"X6S"
TOLERANCE"10%"
VALUE"2.2UF"
VOLTAGE"10V"
PACK_TYPE"C0402"
LOCATION"PC226"
CDS_LIB"pure_quanta"
LOCATION"PC226"
$SEC"1"
CDS_SEC"1";
"B"
$PN"2"20;
"A"
$PN"1"25;
%"Q_RES"
"2","(-7150,-4400)","0","pure_quanta","I12";
;
PART_NUMBER"CS-2202FB01"
PACK_TYPE"0402LF"
WATTAGE"1/16W"
MATERIAL"CHIP"
TOLERANCE"1%"
VALUE"2.2"
LOCATION"PR134"
CDS_LIB"pure_quanta"
LOCATION"PR134"
$SEC"1"
CDS_SEC"1";
"A"
$PN"1"6;
"B"
$PN"2"25;
%"VCC15"
"1","(-7150,-4075)","0","logical_power","I13";
;
HDL_POWER"PVCCIN_CPU0_PVCC"
CDS_LIB"logical_power";
"A"6;
%"UNIVERSAL_GND"
"1","(-6725,-4625)","0","logical_power","I14";
;
CDS_LIB"logical_power"
HDL_POWER"GND"
ROOM"VR_CORE0_CTRL";
"A"19;
%"Q_CAP"
"1","(-6725,-4400)","0","pure_quanta","I15";
;
PART_NUMBER"CH5222KEB01"
MATERIAL"X6S"
TOLERANCE"10%"
VALUE"2.2UF"
VOLTAGE"10V"
PACK_TYPE"C0402"
LOCATION"PC228_P0_8"
CDS_LIB"pure_quanta"
LOCATION"PC228_P0_8"
$SEC"1"
CDS_SEC"1";
"B"
$PN"2"19;
"A"
$PN"1"6;
%"UNIVERSAL_GND"
"1","(-4975,-6125)","0","logical_power","I16";
;
CDS_LIB"logical_power"
HDL_POWER"GND"
ROOM"VR_CORE0_CTRL";
"A"18;
%"Q_CAP"
"1","(-4825,-4500)","0","pure_quanta","I17";
;
PART_NUMBER"TMP_QCH2336K1B12"
MATERIAL"X7R"
TOLERANCE"10%"
VALUE"3300PF"
VOLTAGE"50V"
PACK_TYPE"0402"
LOCATION"PC230_P0_8"
CDS_LIB"pure_quanta"
LOCATION"PC230_P0_8"
$SEC"1"
CDS_SEC"1";
"B"
$PN"2"11;
"A"
$PN"1"4;
%"Q_RES"
"1","(-4375,-4950)","0","pure_quanta","I19";
;
PART_NUMBER"CS-3302FB01"
TOLERANCE"1%"
MATERIAL"CHIP"
WATTAGE"1/16W"
VALUE"3.3"
PACK_TYPE"0402LF"
LOCATION"PR1772"
CDS_LIB"pure_quanta"
$SEC"1"
CDS_SEC"1";
"B"
$PN"2"27;
"A"
$PN"1"26;
%"ISL99390FRZTR5935"
"1","(-5625,-5400)","0","pure_quanta","I2";
;
PART_NUMBER"AL099390004"
PART_TYPE"SMLF"
MATERIAL"IC"
VALUE"ISL99390FRZ-TR5935"
LOCATION"PU6_P0_8"
NEEDS_NO_SIZE"TRUE"
CDS_LMAN_SYM_OUTLINE"-300,700,250,-650"
CDS_LIB"pure_quanta"
$SEC"1"
CDS_SEC"1";
"PGND2"
$PN"7_9-20_24"18;
"GL2"
$PN"41"0;
"GL1"
$PN"6"0;
"DNC"
$PN"31"0;
"EN"
$PN"35"25;
"PGND3"
$PN"40"18;
"VOS"
$PN"1"44;
"VIN2"
$PN"30"4;
"PGND1"
$PN"5"18;
"SW"
$PN"10_19"41;
"LSET"
$PN"37"47;
"IOUT"
$PN"38"23;
"TOUT_FLT"
$PN"36"46;
"PVCC"
$PN"4"6;
"PHASE"
$PN"32"40;
"VIN1"
$PN"25_29"4;
"BOOT"
$PN"33"26;
"AGND"
$PN"2"18;
"VCC"
$PN"3"25;
"REFIN"
$PN"39"24;
"PWM"
$PN"34"45;
%"Q_CAP"
"1","(-4425,-4500)","0","pure_quanta","I20";
;
PART_NUMBER"CH5103KEB01"
MATERIAL"X6S"
TOLERANCE"10%"
VALUE"1UF"
VOLTAGE"16V"
PACK_TYPE"C0402"
LOCATION"PC232_P0_8"
CDS_LIB"pure_quanta"
LOCATION"PC232_P0_8"
$SEC"1"
CDS_SEC"1";
"B"
$PN"2"11;
"A"
$PN"1"4;
%"Q_CAP"
"1","(-4025,-4500)","0","pure_quanta","I21";
;
PART_NUMBER"CH6223MEA01"
MATERIAL"X6S"
TOLERANCE"20%"
VALUE"22UF"
VOLTAGE"16V"
PACK_TYPE"C0805"
LOCATION"PC236_P0_8"
CDS_LIB"pure_quanta"
LOCATION"PC236_P0_8"
$SEC"1"
CDS_SEC"1";
"B"
$PN"2"11;
"A"
$PN"1"4;
%"UNIVERSAL_GND"
"1","(-7525,-3300)","0","logical_power","I22";
;
CDS_LIB"logical_power"
HDL_POWER"GND"
ROOM"VR_CORE0_CTRL";
"A"17;
%"Q_RES"
"2","(-7525,-3075)","2","pure_quanta","I23";
;
PART_NUMBER"CS28872FB01"
WATTAGE"1/16W"
MATERIAL"EMPTY"
TOLERANCE"1%"
VALUE"8.87K"
PACK_TYPE"0402LF"
LOCATION"PR133"
CDS_LIB"pure_quanta"
$SEC"1"
CDS_SEC"1";
"A"
$PN"1"34;
"B"
$PN"2"17;
%"UNIVERSAL_GND"
"1","(-7625,-2850)","0","logical_power","I26";
;
CDS_LIB"logical_power"
HDL_POWER"GND";
"A"16;
%"Q_CAP"
"2","(-6950,-2775)","0","pure_quanta","I29";
;
PART_NUMBER"CH4104K1B00"
VALUE"0.1UF"
MATERIAL"X7R"
TOLERANCE"10%"
PACK_TYPE"0402"
VOLTAGE"25V"
LOCATION"PC1345"
CDS_LIB"pure_quanta"
$SEC"1"
CDS_SEC"1";
"A"
$PN"1"16;
"B"
$PN"2"35;
%"UNIVERSAL_GND"
"1","(-7650,-5675)","0","logical_power","I3";
;
CDS_LIB"logical_power"
HDL_POWER"GND";
"A"21;
%"UNIVERSAL_GND"
"1","(-7125,-2325)","0","logical_power","I30";
;
CDS_LIB"logical_power"
HDL_POWER"GND"
ROOM"VR_CORE0_CTRL";
"A"15;
%"Q_CAP"
"1","(-7125,-2075)","0","pure_quanta","I31";
;
PART_NUMBER"CH5222KEB01"
MATERIAL"X6S"
TOLERANCE"10%"
VALUE"2.2UF"
VOLTAGE"10V"
PACK_TYPE"C0402"
LOCATION"PC227"
CDS_LIB"pure_quanta"
LOCATION"PC227"
$SEC"1"
CDS_SEC"1";
"B"
$PN"2"15;
"A"
$PN"1"33;
%"ISL99390FRZTR5935"
"1","(-5600,-2575)","0","pure_quanta","I32";
;
PART_NUMBER"AL099390004"
PART_TYPE"SMLF"
VALUE"ISL99390FRZ-TR5935"
MATERIAL"IC"
LOCATION"PU7_P0_7"
NEEDS_NO_SIZE"TRUE"
CDS_LMAN_SYM_OUTLINE"-300,700,250,-650"
CDS_LIB"pure_quanta"
$SEC"1"
CDS_SEC"1";
"PGND2"
$PN"7_9-20_24"13;
"GL2"
$PN"41"0;
"GL1"
$PN"6"0;
"DNC"
$PN"31"0;
"EN"
$PN"35"33;
"PGND3"
$PN"40"13;
"VOS"
$PN"1"38;
"VIN2"
$PN"30"2;
"PGND1"
$PN"5"13;
"SW"
$PN"10_19"32;
"LSET"
$PN"37"34;
"IOUT"
$PN"38"37;
"TOUT_FLT"
$PN"36"36;
"PVCC"
$PN"4"5;
"PHASE"
$PN"32"31;
"VIN1"
$PN"25_29"2;
"BOOT"
$PN"33"30;
"AGND"
$PN"2"13;
"VCC"
$PN"3"33;
"REFIN"
$PN"39"35;
"PWM"
$PN"34"43;
%"Q_RES"
"2","(-7125,-1575)","0","pure_quanta","I33";
;
PART_NUMBER"CS-2202FB01"
WATTAGE"1/16W"
MATERIAL"CHIP"
TOLERANCE"1%"
VALUE"2.2"
PACK_TYPE"0402LF"
LOCATION"PR135"
CDS_LIB"pure_quanta"
LOCATION"PR135"
$SEC"1"
CDS_SEC"1";
"A"
$PN"1"5;
"B"
$PN"2"33;
%"VCC15"
"1","(-7125,-1250)","0","logical_power","I34";
;
HDL_POWER"PVCCIN_CPU0_PVCC"
CDS_LIB"logical_power";
"A"5;
%"UNIVERSAL_GND"
"1","(-6700,-1800)","0","logical_power","I35";
;
CDS_LIB"logical_power"
HDL_POWER"GND"
ROOM"VR_CORE0_CTRL";
"A"14;
%"Q_CAP"
"1","(-6700,-1575)","0","pure_quanta","I36";
;
PART_NUMBER"CH5222KEB01"
MATERIAL"X6S"
TOLERANCE"10%"
VALUE"2.2UF"
VOLTAGE"10V"
PACK_TYPE"C0402"
LOCATION"PC229_P0_7"
CDS_LIB"pure_quanta"
LOCATION"PC229_P0_7"
$SEC"1"
CDS_SEC"1";
"B"
$PN"2"14;
"A"
$PN"1"5;
%"UNIVERSAL_GND"
"1","(-4950,-3300)","0","logical_power","I37";
;
CDS_LIB"logical_power"
HDL_POWER"GND"
ROOM"VR_CORE0_CTRL";
"A"13;
%"UNIVERSAL_GND"
"1","(-4550,-2925)","0","logical_power","I38";
;
CDS_LIB"logical_power"
HDL_POWER"GND";
"A"12;
%"Q_INDUCTOR"
"1","(-4325,-2800)","2","pure_quanta","I39";
;
PART_NUMBER"CV+12^0EZ03"
VALUE"120NH/69A"
PACK_TYPE"SMLF"
MATERIAL"IND"
LOCATION"PL105"
CDS_LIB"pure_quanta"
NEEDS_NO_SIZE"TRUE"
$SEC"1"
CDS_SEC"1";
"1"
$PN"1"28;
"2"
$PN"2"12;
%"Q_RES"
"2","(-7550,-5900)","2","pure_quanta","I4";
;
PART_NUMBER"CS28872FB01"
WATTAGE"1/16W"
MATERIAL"EMPTY"
TOLERANCE"1%"
VALUE"8.87K"
PACK_TYPE"0402LF"
LOCATION"PR132"
CDS_LIB"pure_quanta"
$SEC"1"
CDS_SEC"1";
"A"
$PN"1"47;
"B"
$PN"2"22;
%"Q_RES"
"1","(-4350,-2125)","0","pure_quanta","I40";
;
PART_NUMBER"CS-3302FB01"
VALUE"3.3"
WATTAGE"1/16W"
TOLERANCE"1%"
PACK_TYPE"0402LF"
MATERIAL"CHIP"
LOCATION"PR1773"
CDS_LIB"pure_quanta"
$SEC"1"
CDS_SEC"1";
"B"
$PN"2"29;
"A"
$PN"1"30;
%"Q_CAP"
"1","(-4800,-1675)","0","pure_quanta","I41";
;
PART_NUMBER"TMP_QCH2336K1B12"
MATERIAL"X7R"
TOLERANCE"10%"
VALUE"3300PF"
VOLTAGE"50V"
PACK_TYPE"0402"
LOCATION"PC231_P0_7"
CDS_LIB"pure_quanta"
LOCATION"PC231_P0_7"
$SEC"1"
CDS_SEC"1";
"B"
$PN"2"8;
"A"
$PN"1"2;
%"Q_CAP"
"1","(-4400,-1675)","0","pure_quanta","I42";
;
PART_NUMBER"CH5103KEB01"
MATERIAL"X6S"
PACK_TYPE"C0402"
TOLERANCE"10%"
VOLTAGE"16V"
VALUE"1UF"
LOCATION"PC233_P0_7"
CDS_LIB"pure_quanta"
LOCATION"PC233_P0_7"
$SEC"1"
CDS_SEC"1";
"B"
$PN"2"8;
"A"
$PN"1"2;
%"Q_CAP"
"1","(-4000,-1675)","0","pure_quanta","I43";
;
PART_NUMBER"CH6223MEA01"
MATERIAL"X6S"
TOLERANCE"20%"
VALUE"22UF"
VOLTAGE"16V"
PACK_TYPE"C0805"
LOCATION"PC237_P0_7"
CDS_LIB"pure_quanta"
LOCATION"PC237_P0_7"
$SEC"1"
CDS_SEC"1";
"B"
$PN"2"8;
"A"
$PN"1"2;
%"Q_INDUCTOR4P_14"
"1","(-3175,-5525)","0","pure_quanta","I44";
;
PART_NUMBER"CV+15^0TZ04"
MATERIAL"IND"
VALUE"150NH"
PART_TYPE"SMLF"
LOCATION"PL7"
SEC_TYPE""
CDS_LIB"pure_quanta"
NEEDS_NO_SIZE"TRUE"
SEC"1";
"1"
$PN"1"41;
"4"
$PN"4"3;
"3"
$PN"3"10;
"2"
$PN"2"42;
%"Q_CAP"
"1","(-3650,-5125)","2","pure_quanta","I45";
;
PART_NUMBER"CH4106K1B01"
VALUE"100NF"
VOLTAGE"50V"
PACK_TYPE"C0402"
MATERIAL"X7R"
TOLERANCE"10%"
LOCATION"PC234"
CDS_LIB"pure_quanta"
$SEC"1"
CDS_SEC"1";
"B"
$PN"2"40;
"A"
$PN"1"27;
%"Q_RES"
"1","(-3150,-5900)","0","pure_quanta","I46";
;
PART_NUMBER"CS00002JB13"
WATTAGE"1/16W"
MATERIAL"CHIP"
TOLERANCE"5%"
VALUE"0"
PACK_TYPE"0402LF"
LOCATION"PR136"
CDS_LIB"pure_quanta"
$SEC"1"
CDS_SEC"1";
"B"
$PN"2"3;
"A"
$PN"1"44;
%"Q_CAP"
"1","(-3625,-4500)","0","pure_quanta","I47";
;
PART_NUMBER"CH6223MEA01"
PACK_TYPE"C0805"
VALUE"22UF"
MATERIAL"X6S"
TOLERANCE"20%"
VOLTAGE"16V"
LOCATION"PC238_P0_8"
CDS_LIB"pure_quanta"
LOCATION"PC238_P0_8"
$SEC"1"
CDS_SEC"1";
"B"
$PN"2"11;
"A"
$PN"1"4;
%"Q_CAP"
"1","(-3250,-4500)","0","pure_quanta","I48";
;
PART_NUMBER"CH6223MEA01"
PACK_TYPE"C0805"
MATERIAL"X6S"
TOLERANCE"20%"
VOLTAGE"16V"
VALUE"22UF"
LOCATION"PC240_P0_8"
CDS_LIB"pure_quanta"
LOCATION"PC240_P0_8"
$SEC"1"
CDS_SEC"1";
"B"
$PN"2"11;
"A"
$PN"1"4;
%"UNIVERSAL_GND"
"1","(-3025,-4925)","0","logical_power","I49";
;
CDS_LIB"logical_power"
HDL_POWER"GND"
ROOM"VR_CORE0_CTRL";
"A"11;
%"VCC15"
"1","(-3025,-4125)","0","logical_power","I50";
;
HDL_POWER"SW_P12V_PVCCIN_CPU0_FLT"
CDS_LIB"logical_power";
"A"4;
%"UNIVERSAL_GND"
"1","(-2475,-5750)","0","logical_power","I51";
;
CDS_LIB"logical_power"
HDL_POWER"GND";
"A"10;
%"Q_CAP"
"1","(-1575,-5600)","0","pure_quanta","I52";
;
PART_NUMBER"CH5103KEB01"
PACK_TYPE"C0402"
TOLERANCE"10%"
VOLTAGE"16V"
VALUE"1UF"
MATERIAL"X6S"
LOCATION"PC242_P0_8"
CDS_LIB"pure_quanta"
LOCATION"PC242_P0_8"
$SEC"1"
CDS_SEC"1";
"B"
$PN"2"9;
"A"
$PN"1"3;
%"Q_CAP"
"1","(-1150,-5600)","0","pure_quanta","I53";
;
PART_NUMBER"CH622KMEA03"
VOLTAGE"4V"
VALUE"22UF"
TOLERANCE"20%"
MATERIAL"X6S"
PACK_TYPE"C0805"
LOCATION"PC244_P0_8"
CDS_LIB"pure_quanta"
LOCATION"PC244_P0_8"
$SEC"1"
CDS_SEC"1";
"B"
$PN"2"9;
"A"
$PN"1"3;
%"Q_CAP"
"1","(-725,-5600)","0","pure_quanta","I54";
;
PART_NUMBER"CH622KMEA03"
VOLTAGE"4V"
VALUE"22UF"
TOLERANCE"20%"
MATERIAL"X6S"
PACK_TYPE"C0805"
LOCATION"PC246_P0_8"
CDS_LIB"pure_quanta"
LOCATION"PC246_P0_8"
$SEC"1"
CDS_SEC"1";
"B"
$PN"2"9;
"A"
$PN"1"3;
%"UNIVERSAL_GND"
"1","(-425,-5975)","0","logical_power","I55";
;
CDS_LIB"logical_power"
HDL_POWER"GND"
ROOM"VR_CORE0_CTRL";
"A"9;
%"VCC15"
"1","(-425,-5200)","0","logical_power","I56";
;
HDL_POWER"PVCCIN_CPU0"
CDS_LIB"logical_power";
"A"3;
%"Q_RES"
"1","(-3100,-3175)","0","pure_quanta","I57";
;
PART_NUMBER"CS00002JB13"
WATTAGE"1/16W"
PACK_TYPE"0402LF"
MATERIAL"CHIP"
TOLERANCE"5%"
VALUE"0"
LOCATION"PR137"
CDS_LIB"pure_quanta"
$SEC"1"
CDS_SEC"1";
"B"
$PN"2"1;
"A"
$PN"1"38;
%"Q_INDUCTOR4P_14"
"1","(-3350,-2700)","0","pure_quanta","I58";
;
PART_NUMBER"CV+15^0TZ04"
MATERIAL"IND"
PART_TYPE"SMLF"
VALUE"150NH"
LOCATION"PL8"
SEC_TYPE""
CDS_LIB"pure_quanta"
NEEDS_NO_SIZE"TRUE"
SEC"1";
"1"
$PN"1"32;
"4"
$PN"4"1;
"3"
$PN"3"39;
"2"
$PN"2"28;
%"Q_CAP"
"1","(-3625,-2300)","2","pure_quanta","I59";
;
PART_NUMBER"CH4106K1B01"
VALUE"100NF"
VOLTAGE"50V"
TOLERANCE"10%"
MATERIAL"X7R"
PACK_TYPE"C0402"
LOCATION"PC235"
CDS_LIB"pure_quanta"
$SEC"1"
CDS_SEC"1";
"B"
$PN"2"31;
"A"
$PN"1"29;
%"UNIVERSAL_GND"
"1","(-3000,-2100)","0","logical_power","I60";
;
CDS_LIB"logical_power"
HDL_POWER"GND"
ROOM"VR_CORE0_CTRL";
"A"8;
%"Q_CAP"
"1","(-1825,-2775)","0","pure_quanta","I62";
;
PART_NUMBER"CH5103KEB01"
MATERIAL"X6S"
PACK_TYPE"C0402"
TOLERANCE"10%"
VOLTAGE"16V"
VALUE"1UF"
LOCATION"PC243_P0_7"
CDS_LIB"pure_quanta"
LOCATION"PC243_P0_7"
$SEC"1"
CDS_SEC"1";
"B"
$PN"2"7;
"A"
$PN"1"1;
%"Q_CAP"
"1","(-3600,-1675)","0","pure_quanta","I63";
;
PART_NUMBER"CH6223MEA01"
MATERIAL"X6S"
TOLERANCE"20%"
VALUE"22UF"
VOLTAGE"16V"
PACK_TYPE"C0805"
LOCATION"PC239_P0_7"
CDS_LIB"pure_quanta"
LOCATION"PC239_P0_7"
$SEC"1"
CDS_SEC"1";
"B"
$PN"2"8;
"A"
$PN"1"2;
%"Q_CAP"
"1","(-3225,-1675)","0","pure_quanta","I64";
;
PART_NUMBER"CH6223MEA01"
MATERIAL"X6S"
TOLERANCE"20%"
VALUE"22UF"
VOLTAGE"16V"
PACK_TYPE"C0805"
LOCATION"PC241_P0_7"
CDS_LIB"pure_quanta"
LOCATION"PC241_P0_7"
$SEC"1"
CDS_SEC"1";
"B"
$PN"2"8;
"A"
$PN"1"2;
%"VCC15"
"1","(-3000,-1300)","0","logical_power","I65";
;
HDL_POWER"SW_P12V_PVCCIN_CPU0_FLT"
CDS_LIB"logical_power";
"A"2;
%"Q_CAP"
"1","(-1400,-2775)","0","pure_quanta","I66";
;
PART_NUMBER"CH622KMEA03"
VALUE"22UF"
TOLERANCE"20%"
MATERIAL"X6S"
PACK_TYPE"C0805"
VOLTAGE"4V"
LOCATION"PC245_P0_7"
CDS_LIB"pure_quanta"
LOCATION"PC245_P0_7"
$SEC"1"
CDS_SEC"1";
"B"
$PN"2"7;
"A"
$PN"1"1;
%"Q_CAP"
"1","(-975,-2775)","0","pure_quanta","I67";
;
PART_NUMBER"CH622KMEA03"
VOLTAGE"4V"
VALUE"22UF"
TOLERANCE"20%"
MATERIAL"X6S"
PACK_TYPE"C0805"
LOCATION"PC247_P0_7"
CDS_LIB"pure_quanta"
LOCATION"PC247_P0_7"
$SEC"1"
CDS_SEC"1";
"B"
$PN"2"7;
"A"
$PN"1"1;
%"UNIVERSAL_GND"
"1","(-675,-3150)","0","logical_power","I68";
;
CDS_LIB"logical_power"
HDL_POWER"GND"
ROOM"VR_CORE0_CTRL";
"A"7;
%"VCC15"
"1","(-675,-2375)","0","logical_power","I69";
;
HDL_POWER"PVCCIN_CPU0"
CDS_LIB"logical_power";
"A"1;
%"Q_CAP"
"2","(-7025,-5600)","0","pure_quanta","I7";
;
PART_NUMBER"CH4104K1B00"
VALUE"0.1UF"
VOLTAGE"25V"
TOLERANCE"10%"
MATERIAL"X7R"
PACK_TYPE"0402"
LOCATION"PC1344"
CDS_LIB"pure_quanta"
$SEC"1"
CDS_SEC"1";
"A"
$PN"1"21;
"B"
$PN"2"24;
END.
